(kicad_pcb
	(version 20260206)
	(generator "pcbnew")
	(generator_version "10.0")
	(general
		(thickness 1.6)
		(legacy_teardrops no)
	)
	(paper "A4")
	(title_block
		(title "baseboard — 13948-1b.1110WZS1818.brd")
		(comment 1 "Honey Badger (Wiwynn) / footprints 720-727 of 2523")
	)
	(layers
		(0 "F.Cu" signal "TOP")
		(4 "In1.Cu" signal "L2GND")
		(6 "In2.Cu" signal "L3")
		(8 "In3.Cu" signal "L4VCC")
		(10 "In4.Cu" signal "L5VCC")
		(12 "In5.Cu" signal "L6")
		(14 "In6.Cu" signal "L7GND")
		(2 "B.Cu" signal "BOTTOM")
		(9 "F.Adhes" user "F.Adhesive")
		(11 "B.Adhes" user "B.Adhesive")
		(13 "F.Paste" user "Package Geometry/Pastemask Top")
		(15 "B.Paste" user "Package Geometry/Pastemask Bottom")
		(5 "F.SilkS" user "Ref Des/Silkscreen Top")
		(7 "B.SilkS" user "Ref Des/Silkscreen Bottom")
		(1 "F.Mask" user "Board Geometry/Soldermask Top")
		(3 "B.Mask" user "Board Geometry/Soldermask Bottom")
		(17 "Dwgs.User" user "User.Drawings")
		(19 "Cmts.User" user "User.Comments")
		(21 "Eco1.User" user "User.Eco1")
		(23 "Eco2.User" user "User.Eco2")
		(25 "Edge.Cuts" user "Board Geometry/Outline")
		(27 "Margin" user)
		(31 "F.CrtYd" user "Package Geometry/Place Bound Top")
		(29 "B.CrtYd" user "Package Geometry/Place Bound Bottom")
		(35 "F.Fab" user "Ref Des/Assembly Top")
		(33 "B.Fab" user "Ref Des/Assembly Bottom")
	)
	(footprint ""
		(layer "F.Cu")
		(at 132.72897 -98.806 180)
		(property "Reference" "SC1271"
			(at 0 0 180)
			(layer "F.SilkS")
			(hide yes)
			(effects
				(font
					(size 1.27 1.27)
				)
			)
		)
		(property "Value" "SCD01U10V1KX-GP"
			(at -2.8321 -1.7399 180)
			(unlocked yes)
			(layer "F.Fab")
			(hide yes)
			(effects
				(font
					(size 1.016 1.016)
					(thickness 0.1524)
				)
			)
		)
		(property "Device Type" "C0201H13"
			(at -2.8321 -3.2639 180)
			(unlocked yes)
			(layer "F.Fab")
			(hide yes)
			(effects
				(font
					(size 1.016 1.016)
					(thickness 0.1524)
				)
			)
		)
		(duplicate_pad_numbers_are_jumpers no)
		(fp_rect
			(start -0.2794 0.6477)
			(end 0.2794 -0.6477)
			(stroke
				(width 0)
				(type default)
			)
			(fill no)
			(layer "F.CrtYd")
		)
		(fp_rect
			(start -0.2794 0.6477)
			(end 0.2794 -0.6477)
			(stroke
				(width 0)
				(type default)
			)
			(fill no)
			(layer "F.Fab")
		)
		(pad "1" smd custom
			(at 0 -0.2794 180)
			(size 0.0762 0.0762)
			(layers "F.Cu" "F.Mask" "F.Paste")
			(net "3X24_SAS_TX22_N")
			(options
				(clearance outline)
				(anchor circle)
			)
			(primitives
				(gr_poly
					(pts
						(arc
							(start 0.1524 -0.127)
							(mid 0.137521 -0.162921)
							(end 0.1016 -0.1778)
						)
						(arc
							(start -0.1016 -0.1778)
							(mid -0.137521 -0.162921)
							(end -0.1524 -0.127)
						)
						(arc
							(start -0.1524 0.127)
							(mid -0.137521 0.162921)
							(end -0.1016 0.1778)
						)
						(arc
							(start 0.1016 0.1778)
							(mid 0.137521 0.162921)
							(end 0.1524 0.127)
						)
					)
					(width 0)
					(fill yes)
				)
			)
		)
		(pad "2" smd custom
			(at 0 0.2794 180)
			(size 0.0762 0.0762)
			(layers "F.Cu" "F.Mask" "F.Paste")
			(net "SAS_EXP_GF_TX_DN2")
			(options
				(clearance outline)
				(anchor circle)
			)
			(primitives
				(gr_poly
					(pts
						(arc
							(start 0.1524 -0.127)
							(mid 0.137521 -0.162921)
							(end 0.1016 -0.1778)
						)
						(arc
							(start -0.1016 -0.1778)
							(mid -0.137521 -0.162921)
							(end -0.1524 -0.127)
						)
						(arc
							(start -0.1524 0.127)
							(mid -0.137521 0.162921)
							(end -0.1016 0.1778)
						)
						(arc
							(start 0.1016 0.1778)
							(mid 0.137521 0.162921)
							(end 0.1524 0.127)
						)
					)
					(width 0)
					(fill yes)
				)
			)
		)
	)
	(footprint ""
		(layer "F.Cu")
		(at 16.079216 -181.91988)
		(property "Reference" "R648"
			(at 0 0 0)
			(layer "F.SilkS")
			(hide yes)
			(effects
				(font
					(size 1.27 1.27)
				)
			)
		)
		(property "Value" "4K7R2F-GP"
			(at 0.064008 -3.993896 0)
			(unlocked yes)
			(layer "F.Fab")
			(hide yes)
			(effects
				(font
					(size 1.016 1.016)
					(thickness 0.1524)
				)
			)
		)
		(property "Device Type" "R402H16"
			(at 0.064008 -5.517896 0)
			(unlocked yes)
			(layer "F.Fab")
			(hide yes)
			(effects
				(font
					(size 1.016 1.016)
					(thickness 0.1524)
				)
			)
		)
		(duplicate_pad_numbers_are_jumpers no)
		(fp_line
			(start -0.508 -0.9398)
			(end -0.508 0.9398)
			(stroke
				(width 0.1524)
				(type default)
			)
			(layer "F.SilkS")
		)
		(fp_line
			(start 0.508 -0.9398)
			(end -0.508 -0.9398)
			(stroke
				(width 0.1524)
				(type default)
			)
			(layer "F.SilkS")
		)
		(fp_rect
			(start -0.508 0.9398)
			(end 0.508 -0.9398)
			(stroke
				(width 0)
				(type default)
			)
			(fill no)
			(layer "F.CrtYd")
		)
		(fp_rect
			(start -0.508 0.9398)
			(end 0.508 -0.9398)
			(stroke
				(width 0)
				(type default)
			)
			(fill no)
			(layer "F.Fab")
		)
		(pad "1" smd custom
			(at 0 -0.4445)
			(size 0.1397 0.1397)
			(layers "F.Cu" "F.Mask" "F.Paste")
			(net "IO_EXP_HDD_PRE_A2")
			(options
				(clearance outline)
				(anchor circle)
			)
			(primitives
				(gr_poly
					(pts
						(arc
							(start -0.1778 -0.2794)
							(mid -0.249642 -0.249642)
							(end -0.2794 -0.1778)
						)
						(arc
							(start -0.2794 0.1778)
							(mid -0.249642 0.249642)
							(end -0.1778 0.2794)
						)
						(arc
							(start 0.1778 0.2794)
							(mid 0.249642 0.249642)
							(end 0.2794 0.1778)
						)
						(arc
							(start 0.2794 -0.1778)
							(mid 0.249642 -0.249642)
							(end 0.1778 -0.2794)
						)
					)
					(width 0)
					(fill yes)
				)
			)
		)
		(pad "2" smd custom
			(at 0 0.4445)
			(size 0.1397 0.1397)
			(layers "F.Cu" "F.Mask" "F.Paste")
			(net "GND")
			(options
				(clearance outline)
				(anchor circle)
			)
			(primitives
				(gr_poly
					(pts
						(arc
							(start -0.1778 -0.2794)
							(mid -0.249642 -0.249642)
							(end -0.2794 -0.1778)
						)
						(arc
							(start -0.2794 0.1778)
							(mid -0.249642 0.249642)
							(end -0.1778 0.2794)
						)
						(arc
							(start 0.1778 0.2794)
							(mid 0.249642 0.249642)
							(end 0.2794 0.1778)
						)
						(arc
							(start 0.2794 -0.1778)
							(mid 0.249642 -0.249642)
							(end 0.1778 -0.2794)
						)
					)
					(width 0)
					(fill yes)
				)
			)
		)
	)
	(footprint ""
		(layer "F.Cu")
		(at 208.391252 -111.64316)
		(property "Reference" "PC227"
			(at 0 0 0)
			(layer "F.SilkS")
			(hide yes)
			(effects
				(font
					(size 1.27 1.27)
				)
			)
		)
		(property "Value" "SC22U25V5MX-GP"
			(at -0.0762 -6.1214 0)
			(unlocked yes)
			(layer "F.Fab")
			(hide yes)
			(effects
				(font
					(size 1.016 1.016)
					(thickness 0.1524)
				)
			)
		)
		(property "Device Type" "C805H58"
			(at -0.0762 -8.1534 0)
			(unlocked yes)
			(layer "F.Fab")
			(hide yes)
			(effects
				(font
					(size 1.016 1.016)
					(thickness 0.1524)
				)
			)
		)
		(duplicate_pad_numbers_are_jumpers no)
		(fp_line
			(start 0.635 0)
			(end -0.635 0)
			(stroke
				(width 0.508)
				(type default)
			)
			(layer "F.SilkS")
		)
		(fp_rect
			(start -0.9652 1.778)
			(end 0.9652 -1.778)
			(stroke
				(width 0)
				(type default)
			)
			(fill no)
			(layer "F.CrtYd")
		)
		(fp_poly
			(pts
				(xy -0.9652 -1.778) (xy 0.9652 -1.778) (xy 0.9652 1.778) (xy -0.9652 1.778)
			)
			(stroke
				(width 0)
				(type default)
			)
			(fill no)
			(layer "F.Fab")
		)
		(pad "1" smd rect
			(at 0 -0.9652)
			(size 1.397 1.143)
			(layers "F.Cu" "F.Mask" "F.Paste")
			(net "P1V5_E_VIN")
		)
		(pad "2" smd rect
			(at 0 0.9652)
			(size 1.397 1.143)
			(layers "F.Cu" "F.Mask" "F.Paste")
			(net "GND")
		)
	)
	(footprint ""
		(layer "F.Cu")
		(at 319.913 -167.894 -90)
		(property "Reference" "R440"
			(at 0 0 270)
			(layer "F.SilkS")
			(hide yes)
			(effects
				(font
					(size 1.27 1.27)
				)
			)
		)
		(property "Value" "10KR2F-2-GP"
			(at 0.064008 -3.993896 270)
			(unlocked yes)
			(layer "F.Fab")
			(hide yes)
			(effects
				(font
					(size 1.016 1.016)
					(thickness 0.1524)
				)
			)
		)
		(property "Device Type" "R402H16"
			(at 0.064008 -5.517896 270)
			(unlocked yes)
			(layer "F.Fab")
			(hide yes)
			(effects
				(font
					(size 1.016 1.016)
					(thickness 0.1524)
				)
			)
		)
		(duplicate_pad_numbers_are_jumpers no)
		(fp_line
			(start -0.508 -0.9398)
			(end -0.508 0.9398)
			(stroke
				(width 0.1524)
				(type default)
			)
			(layer "F.SilkS")
		)
		(fp_line
			(start 0.508 -0.9398)
			(end -0.508 -0.9398)
			(stroke
				(width 0.1524)
				(type default)
			)
			(layer "F.SilkS")
		)
		(fp_rect
			(start -0.508 0.9398)
			(end 0.508 -0.9398)
			(stroke
				(width 0)
				(type default)
			)
			(fill no)
			(layer "F.CrtYd")
		)
		(fp_rect
			(start -0.508 0.9398)
			(end 0.508 -0.9398)
			(stroke
				(width 0)
				(type default)
			)
			(fill no)
			(layer "F.Fab")
		)
		(pad "1" smd custom
			(at 0 -0.4445 270)
			(size 0.1397 0.1397)
			(layers "F.Cu" "F.Mask" "F.Paste")
			(net "P3V3_STBY")
			(options
				(clearance outline)
				(anchor circle)
			)
			(primitives
				(gr_poly
					(pts
						(arc
							(start -0.1778 -0.2794)
							(mid -0.249642 -0.249642)
							(end -0.2794 -0.1778)
						)
						(arc
							(start -0.2794 0.1778)
							(mid -0.249642 0.249642)
							(end -0.1778 0.2794)
						)
						(arc
							(start 0.1778 0.2794)
							(mid 0.249642 0.249642)
							(end 0.2794 0.1778)
						)
						(arc
							(start 0.2794 -0.1778)
							(mid 0.249642 -0.249642)
							(end 0.1778 -0.2794)
						)
					)
					(width 0)
					(fill yes)
				)
			)
		)
		(pad "2" smd custom
			(at 0 0.4445 270)
			(size 0.1397 0.1397)
			(layers "F.Cu" "F.Mask" "F.Paste")
			(net "BMC_I2C_B_SDA")
			(options
				(clearance outline)
				(anchor circle)
			)
			(primitives
				(gr_poly
					(pts
						(arc
							(start -0.1778 -0.2794)
							(mid -0.249642 -0.249642)
							(end -0.2794 -0.1778)
						)
						(arc
							(start -0.2794 0.1778)
							(mid -0.249642 0.249642)
							(end -0.1778 0.2794)
						)
						(arc
							(start 0.1778 0.2794)
							(mid 0.249642 0.249642)
							(end 0.2794 0.1778)
						)
						(arc
							(start 0.2794 -0.1778)
							(mid 0.249642 -0.249642)
							(end 0.1778 -0.2794)
						)
					)
					(width 0)
					(fill yes)
				)
			)
		)
	)
	(footprint ""
		(layer "F.Cu")
		(at 116.332 -72.771 90)
		(property "Reference" "TP171"
			(at 0 0 90)
			(layer "F.SilkS")
			(hide yes)
			(effects
				(font
					(size 1.27 1.27)
				)
			)
		)
		(property "Value" "TPAD32-GP"
			(at 0 -3.166364 90)
			(unlocked yes)
			(layer "F.Fab")
			(hide yes)
			(effects
				(font
					(size 1.016 1.016)
					(thickness 0.1524)
				)
			)
		)
		(property "Device Type" "TPAD32"
			(at 0 -4.690618 90)
			(unlocked yes)
			(layer "F.Fab")
			(hide yes)
			(effects
				(font
					(size 1.016 1.016)
					(thickness 0.1524)
				)
			)
		)
		(duplicate_pad_numbers_are_jumpers no)
		(fp_poly
			(pts
				(arc
					(start 0 0.4064)
					(mid 0 -0.4064)
					(end 0 0.4064)
				)
			)
			(stroke
				(width 0)
				(type default)
			)
			(fill no)
			(layer "F.CrtYd")
		)
		(fp_poly
			(pts
				(arc
					(start 0 0.7112)
					(mid 0 -0.7112)
					(end 0 0.7112)
				)
			)
			(stroke
				(width 0)
				(type default)
			)
			(fill no)
			(layer "F.Fab")
		)
		(pad "1" smd circle
			(at 0 0 90)
			(size 0.8128 0.8128)
			(layers "F.Cu" "F.Mask" "F.Paste")
			(net "TEMP_4_ALERT")
		)
	)
	(footprint ""
		(layer "F.Cu")
		(at 330.399136 -211.463128 180)
		(property "Reference" "C152"
			(at 0 0 180)
			(layer "F.SilkS")
			(hide yes)
			(effects
				(font
					(size 1.27 1.27)
				)
			)
		)
		(property "Value" "SCD1U16V2JX-1-GP"
			(at 1.1811 -2.7051 180)
			(unlocked yes)
			(layer "F.Fab")
			(hide yes)
			(effects
				(font
					(size 1.016 1.016)
					(thickness 0.1524)
				)
			)
		)
		(property "Device Type" "C402H22"
			(at 1.1811 -4.2291 180)
			(unlocked yes)
			(layer "F.Fab")
			(hide yes)
			(effects
				(font
					(size 1.016 1.016)
					(thickness 0.1524)
				)
			)
		)
		(duplicate_pad_numbers_are_jumpers no)
		(fp_rect
			(start -0.4318 0.9525)
			(end 0.4318 -0.9525)
			(stroke
				(width 0)
				(type default)
			)
			(fill no)
			(layer "F.CrtYd")
		)
		(fp_rect
			(start -0.4318 0.9525)
			(end 0.4318 -0.9525)
			(stroke
				(width 0)
				(type default)
			)
			(fill no)
			(layer "F.Fab")
		)
		(pad "1" smd custom
			(at 0 -0.4445 180)
			(size 0.1524 0.1524)
			(layers "F.Cu" "F.Mask" "F.Paste")
			(net "P3V3_STBY")
			(options
				(clearance outline)
				(anchor circle)
			)
			(primitives
				(gr_poly
					(pts
						(arc
							(start 0.3048 -0.2032)
							(mid 0.275042 -0.275042)
							(end 0.2032 -0.3048)
						)
						(arc
							(start -0.2032 -0.3048)
							(mid -0.275042 -0.275042)
							(end -0.3048 -0.2032)
						)
						(arc
							(start -0.3048 0.2032)
							(mid -0.275042 0.275042)
							(end -0.2032 0.3048)
						)
						(arc
							(start 0.2032 0.3048)
							(mid 0.275042 0.275042)
							(end 0.3048 0.2032)
						)
					)
					(width 0)
					(fill yes)
				)
			)
		)
		(pad "2" smd custom
			(at 0 0.4445 180)
			(size 0.1524 0.1524)
			(layers "F.Cu" "F.Mask" "F.Paste")
			(net "GND")
			(options
				(clearance outline)
				(anchor circle)
			)
			(primitives
				(gr_poly
					(pts
						(arc
							(start 0.3048 -0.2032)
							(mid 0.275042 -0.275042)
							(end 0.2032 -0.3048)
						)
						(arc
							(start -0.2032 -0.3048)
							(mid -0.275042 -0.275042)
							(end -0.3048 -0.2032)
						)
						(arc
							(start -0.3048 0.2032)
							(mid -0.275042 0.275042)
							(end -0.2032 0.3048)
						)
						(arc
							(start 0.2032 0.3048)
							(mid 0.275042 0.275042)
							(end 0.3048 0.2032)
						)
					)
					(width 0)
					(fill yes)
				)
			)
		)
	)
	(footprint ""
		(layer "F.Cu")
		(at 172.675804 -25.152096 90)
		(property "Reference" "R388"
			(at 0 0 90)
			(layer "F.SilkS")
			(hide yes)
			(effects
				(font
					(size 1.27 1.27)
				)
			)
		)
		(property "Value" "0R2J-2-GP"
			(at 0.064008 -3.993896 90)
			(unlocked yes)
			(layer "F.Fab")
			(hide yes)
			(effects
				(font
					(size 1.016 1.016)
					(thickness 0.1524)
				)
			)
		)
		(property "Device Type" "R402H16"
			(at 0.064008 -5.517896 90)
			(unlocked yes)
			(layer "F.Fab")
			(hide yes)
			(effects
				(font
					(size 1.016 1.016)
					(thickness 0.1524)
				)
			)
		)
		(duplicate_pad_numbers_are_jumpers no)
		(fp_line
			(start 0.508 -0.9398)
			(end -0.508 -0.9398)
			(stroke
				(width 0.1524)
				(type default)
			)
			(layer "F.SilkS")
		)
		(fp_line
			(start -0.508 -0.9398)
			(end -0.508 0.9398)
			(stroke
				(width 0.1524)
				(type default)
			)
			(layer "F.SilkS")
		)
		(fp_rect
			(start -0.508 0.9398)
			(end 0.508 -0.9398)
			(stroke
				(width 0)
				(type default)
			)
			(fill no)
			(layer "F.CrtYd")
		)
		(fp_rect
			(start -0.508 0.9398)
			(end 0.508 -0.9398)
			(stroke
				(width 0)
				(type default)
			)
			(fill no)
			(layer "F.Fab")
		)
		(pad "1" smd custom
			(at 0 -0.4445 90)
			(size 0.1397 0.1397)
			(layers "F.Cu" "F.Mask" "F.Paste")
			(net "BCM5221_MB_TX_DP")
			(options
				(clearance outline)
				(anchor circle)
			)
			(primitives
				(gr_poly
					(pts
						(arc
							(start -0.1778 -0.2794)
							(mid -0.249642 -0.249642)
							(end -0.2794 -0.1778)
						)
						(arc
							(start -0.2794 0.1778)
							(mid -0.249642 0.249642)
							(end -0.1778 0.2794)
						)
						(arc
							(start 0.1778 0.2794)
							(mid 0.249642 0.249642)
							(end 0.2794 0.1778)
						)
						(arc
							(start 0.2794 -0.1778)
							(mid 0.249642 -0.249642)
							(end 0.1778 -0.2794)
						)
					)
					(width 0)
					(fill yes)
				)
			)
		)
		(pad "2" smd custom
			(at 0 0.4445 90)
			(size 0.1397 0.1397)
			(layers "F.Cu" "F.Mask" "F.Paste")
			(net "BCM5221_TX_C_DP")
			(options
				(clearance outline)
				(anchor circle)
			)
			(primitives
				(gr_poly
					(pts
						(arc
							(start -0.1778 -0.2794)
							(mid -0.249642 -0.249642)
							(end -0.2794 -0.1778)
						)
						(arc
							(start -0.2794 0.1778)
							(mid -0.249642 0.249642)
							(end -0.1778 0.2794)
						)
						(arc
							(start 0.1778 0.2794)
							(mid 0.249642 0.249642)
							(end 0.2794 0.1778)
						)
						(arc
							(start 0.2794 -0.1778)
							(mid 0.249642 -0.249642)
							(end 0.1778 -0.2794)
						)
					)
					(width 0)
					(fill yes)
				)
			)
		)
	)
	(footprint ""
		(layer "F.Cu")
		(at 152.247092 -112.043464 -90)
		(property "Reference" "SR832"
			(at 0 0 270)
			(layer "F.SilkS")
			(hide yes)
			(effects
				(font
					(size 1.27 1.27)
				)
			)
		)
		(property "Value" "D51R3F-2-GP"
			(at -0.0254 -2.5146 270)
			(unlocked yes)
			(layer "F.Fab")
			(hide yes)
			(effects
				(font
					(size 1.016 1.016)
					(thickness 0.1524)
				)
			)
		)
		(property "Device Type" "R603H22"
			(at -0.0254 -4.0386 270)
			(unlocked yes)
			(layer "F.Fab")
			(hide yes)
			(effects
				(font
					(size 1.016 1.016)
					(thickness 0.1524)
				)
			)
		)
		(duplicate_pad_numbers_are_jumpers no)
		(fp_line
			(start -0.4826 0)
			(end -0.2032 0)
			(stroke
				(width 0.2032)
				(type default)
			)
			(layer "F.SilkS")
		)
		(fp_line
			(start 0.2032 0)
			(end 0.4826 0)
			(stroke
				(width 0.2032)
				(type default)
			)
			(layer "F.SilkS")
		)
		(fp_rect
			(start -0.5842 1.3335)
			(end 0.5842 -1.3335)
			(stroke
				(width 0)
				(type default)
			)
			(fill no)
			(layer "F.CrtYd")
		)
		(fp_rect
			(start -0.5842 1.3335)
			(end 0.5842 -1.3335)
			(stroke
				(width 0)
				(type default)
			)
			(fill no)
			(layer "F.Fab")
		)
		(pad "1" smd custom
			(at 0 -0.762 270)
			(size 0.2159 0.2159)
			(layers "F.Cu" "F.Mask" "F.Paste")
			(net "P0V9_E")
			(options
				(clearance outline)
				(anchor circle)
			)
			(primitives
				(gr_poly
					(pts
						(arc
							(start -0.3302 -0.4318)
							(mid -0.402042 -0.402042)
							(end -0.4318 -0.3302)
						)
						(arc
							(start -0.4318 0.3302)
							(mid -0.402042 0.402042)
							(end -0.3302 0.4318)
						)
						(arc
							(start 0.3302 0.4318)
							(mid 0.402042 0.402042)
							(end 0.4318 0.3302)
						)
						(arc
							(start 0.4318 -0.3302)
							(mid 0.402042 -0.402042)
							(end 0.3302 -0.4318)
						)
					)
					(width 0)
					(fill yes)
				)
			)
		)
		(pad "2" smd custom
			(at 0 0.762 270)
			(size 0.2159 0.2159)
			(layers "F.Cu" "F.Mask" "F.Paste")
			(net "GB_VDDA")
			(options
				(clearance outline)
				(anchor circle)
			)
			(primitives
				(gr_poly
					(pts
						(arc
							(start -0.3302 -0.4318)
							(mid -0.402042 -0.402042)
							(end -0.4318 -0.3302)
						)
						(arc
							(start -0.4318 0.3302)
							(mid -0.402042 0.402042)
							(end -0.3302 0.4318)
						)
						(arc
							(start 0.3302 0.4318)
							(mid 0.402042 0.402042)
							(end 0.4318 0.3302)
						)
						(arc
							(start 0.4318 -0.3302)
							(mid 0.402042 -0.402042)
							(end 0.3302 -0.4318)
						)
					)
					(width 0)
					(fill yes)
				)
			)
		)
	)
)
